(kicad_pcb
	(version 20260206)
	(generator "pcbnew")
	(generator_version "10.0")
	(general
		(thickness 1.6)
		(legacy_teardrops no)
	)
	(paper "A4")
	(title_block
		(title "Wiwynn_Tioga_Pass_MB.brd")
		(comment 1 "Tioga Pass / footprint 190 of 4770 (U2D1), pads 1-79 of 3647")
	)
	(layers
		(0 "F.Cu" signal "TOP")
		(4 "In1.Cu" signal "L2GND")
		(6 "In2.Cu" signal "L3")
		(8 "In3.Cu" signal "L4GND")
		(10 "In4.Cu" signal "L5")
		(12 "In5.Cu" signal "L6GND")
		(14 "In6.Cu" signal "L7VCC")
		(16 "In7.Cu" signal "L8VCC")
		(18 "In8.Cu" signal "L9GND")
		(20 "In9.Cu" signal "L10")
		(22 "In10.Cu" signal "L11GND")
		(24 "In11.Cu" signal "L12")
		(26 "In12.Cu" signal "L13GND")
		(2 "B.Cu" signal "BOTTOM")
		(9 "F.Adhes" user "F.Adhesive")
		(11 "B.Adhes" user "B.Adhesive")
		(13 "F.Paste" user "Package Geometry/Pastemask Top")
		(15 "B.Paste" user "Package Geometry/Pastemask Bottom")
		(5 "F.SilkS" user "Ref Des/Silkscreen Top")
		(7 "B.SilkS" user "Ref Des/Silkscreen Bottom")
		(1 "F.Mask" user "Board Geometry/Soldermask Top")
		(3 "B.Mask" user "Board Geometry/Soldermask Bottom")
		(17 "Dwgs.User" user "User.Drawings")
		(19 "Cmts.User" user "User.Comments")
		(21 "Eco1.User" user "User.Eco1")
		(23 "Eco2.User" user "User.Eco2")
		(25 "Edge.Cuts" user "Board Geometry/Outline")
		(27 "Margin" user)
		(31 "F.CrtYd" user "Package Geometry/Place Bound Top")
		(29 "B.CrtYd" user "Package Geometry/Place Bound Bottom")
		(35 "F.Fab" user "Ref Des/Assembly Top")
		(33 "B.Fab" user "Ref Des/Assembly Bottom")
	)
	(footprint ""
		(layer "F.Cu")
		(at 104.99979 -76.550012 180)
		(property "Reference" "U2D1"
			(at 25.19299 30.484318 0)
			(unlocked yes)
			(layer "F.SilkS")
			(effects
				(font
					(size 0.7874 0.5842)
					(thickness 0.1524)
				)
			)
		)
		(property "Value" ""
			(at 0 0 180)
			(layer "F.Fab")
			(effects
				(font
					(size 1.27 1.27)
				)
			)
		)
		(duplicate_pad_numbers_are_jumpers no)
		(pad "A4" smd custom
			(at -34.675064 -25.103074 45)
			(size 0.10795 0.10795)
			(layers "F.Cu" "F.Mask" "F.Paste")
			(net "TP_CPU1_RSVD_304")
			(options
				(clearance outline)
				(anchor circle)
			)
			(primitives
				(gr_poly
					(pts
						(arc
							(start 0.2159 -0.0381)
							(mid 0 -0.254)
							(end -0.2159 -0.0381)
						)
						(arc
							(start -0.2159 0.0381)
							(mid 0 0.254)
							(end 0.2159 0.0381)
						)
					)
					(width 0)
					(fill yes)
				)
			)
		)
		(pad "A6" smd custom
			(at -32.958024 -25.103074 45)
			(size 0.10795 0.10795)
			(layers "F.Cu" "F.Mask" "F.Paste")
			(net "TP_CPU1_RSVD_303")
			(options
				(clearance outline)
				(anchor circle)
			)
			(primitives
				(gr_poly
					(pts
						(arc
							(start 0.2159 -0.0381)
							(mid 0 -0.254)
							(end -0.2159 -0.0381)
						)
						(arc
							(start -0.2159 0.0381)
							(mid 0 0.254)
							(end 0.2159 0.0381)
						)
					)
					(width 0)
					(fill yes)
				)
			)
		)
		(pad "A8" smd custom
			(at -31.240984 -25.103074)
			(size 0.10795 0.10795)
			(layers "F.Cu" "F.Mask" "F.Paste")
			(net "PVPP_GHJ")
			(options
				(clearance outline)
				(anchor circle)
			)
			(primitives
				(gr_poly
					(pts
						(arc
							(start 0.2159 -0.0381)
							(mid 0 -0.254)
							(end -0.2159 -0.0381)
						)
						(arc
							(start -0.2159 0.0381)
							(mid 0 0.254)
							(end 0.2159 0.0381)
						)
					)
					(width 0)
					(fill yes)
				)
			)
		)
		(pad "A10" smd custom
			(at -29.523944 -25.103074)
			(size 0.10795 0.10795)
			(layers "F.Cu" "F.Mask" "F.Paste")
			(net "PVPP_GHJ")
			(options
				(clearance outline)
				(anchor circle)
			)
			(primitives
				(gr_poly
					(pts
						(arc
							(start 0.2159 -0.0381)
							(mid 0 -0.254)
							(end -0.2159 -0.0381)
						)
						(arc
							(start -0.2159 0.0381)
							(mid 0 0.254)
							(end 0.2159 0.0381)
						)
					)
					(width 0)
					(fill yes)
				)
			)
		)
		(pad "A12" smd custom
			(at -27.806904 -25.103074)
			(size 0.10795 0.10795)
			(layers "F.Cu" "F.Mask" "F.Paste")
			(net "PVPP_GHJ")
			(options
				(clearance outline)
				(anchor circle)
			)
			(primitives
				(gr_poly
					(pts
						(arc
							(start 0.2159 -0.0381)
							(mid 0 -0.254)
							(end -0.2159 -0.0381)
						)
						(arc
							(start -0.2159 0.0381)
							(mid 0 0.254)
							(end 0.2159 0.0381)
						)
					)
					(width 0)
					(fill yes)
				)
			)
		)
		(pad "A14" smd custom
			(at -26.090118 -25.103074)
			(size 0.10795 0.10795)
			(layers "F.Cu" "F.Mask" "F.Paste")
			(net "P1V8_MCP_CPU1")
			(options
				(clearance outline)
				(anchor circle)
			)
			(primitives
				(gr_poly
					(pts
						(arc
							(start 0.2159 -0.0381)
							(mid 0 -0.254)
							(end -0.2159 -0.0381)
						)
						(arc
							(start -0.2159 0.0381)
							(mid 0 0.254)
							(end 0.2159 0.0381)
						)
					)
					(width 0)
					(fill yes)
				)
			)
		)
		(pad "A16" smd custom
			(at -24.373078 -25.103074)
			(size 0.10795 0.10795)
			(layers "F.Cu" "F.Mask" "F.Paste")
			(net "P1V8_MCP_CPU1")
			(options
				(clearance outline)
				(anchor circle)
			)
			(primitives
				(gr_poly
					(pts
						(arc
							(start 0.2159 -0.0381)
							(mid 0 -0.254)
							(end -0.2159 -0.0381)
						)
						(arc
							(start -0.2159 0.0381)
							(mid 0 0.254)
							(end 0.2159 0.0381)
						)
					)
					(width 0)
					(fill yes)
				)
			)
		)
		(pad "A24" smd custom
			(at -17.504918 -25.103074)
			(size 0.10795 0.10795)
			(layers "F.Cu" "F.Mask" "F.Paste")
			(net "TP_CPU1_RSVD_300")
			(options
				(clearance outline)
				(anchor circle)
			)
			(primitives
				(gr_poly
					(pts
						(arc
							(start 0.2159 -0.0381)
							(mid 0 -0.254)
							(end -0.2159 -0.0381)
						)
						(arc
							(start -0.2159 0.0381)
							(mid 0 0.254)
							(end 0.2159 0.0381)
						)
					)
					(width 0)
					(fill yes)
				)
			)
		)
		(pad "A26" smd custom
			(at -15.787878 -25.103074)
			(size 0.10795 0.10795)
			(layers "F.Cu" "F.Mask" "F.Paste")
			(net "GND")
			(options
				(clearance outline)
				(anchor circle)
			)
			(primitives
				(gr_poly
					(pts
						(arc
							(start 0.2159 -0.0381)
							(mid 0 -0.254)
							(end -0.2159 -0.0381)
						)
						(arc
							(start -0.2159 0.0381)
							(mid 0 0.254)
							(end 0.2159 0.0381)
						)
					)
					(width 0)
					(fill yes)
				)
			)
		)
		(pad "A28" smd custom
			(at -14.071092 -25.103074)
			(size 0.10795 0.10795)
			(layers "F.Cu" "F.Mask" "F.Paste")
			(net "M_H_DQS_DN<15>")
			(options
				(clearance outline)
				(anchor circle)
			)
			(primitives
				(gr_poly
					(pts
						(arc
							(start 0.2159 -0.0381)
							(mid 0 -0.254)
							(end -0.2159 -0.0381)
						)
						(arc
							(start -0.2159 0.0381)
							(mid 0 0.254)
							(end 0.2159 0.0381)
						)
					)
					(width 0)
					(fill yes)
				)
			)
		)
		(pad "A30" smd custom
			(at -12.354052 -25.103074)
			(size 0.10795 0.10795)
			(layers "F.Cu" "F.Mask" "F.Paste")
			(net "GND")
			(options
				(clearance outline)
				(anchor circle)
			)
			(primitives
				(gr_poly
					(pts
						(arc
							(start 0.2159 -0.0381)
							(mid 0 -0.254)
							(end -0.2159 -0.0381)
						)
						(arc
							(start -0.2159 0.0381)
							(mid 0 0.254)
							(end 0.2159 0.0381)
						)
					)
					(width 0)
					(fill yes)
				)
			)
		)
		(pad "A32" smd custom
			(at -10.637012 -25.103074)
			(size 0.10795 0.10795)
			(layers "F.Cu" "F.Mask" "F.Paste")
			(net "GND")
			(options
				(clearance outline)
				(anchor circle)
			)
			(primitives
				(gr_poly
					(pts
						(arc
							(start 0.2159 -0.0381)
							(mid 0 -0.254)
							(end -0.2159 -0.0381)
						)
						(arc
							(start -0.2159 0.0381)
							(mid 0 0.254)
							(end 0.2159 0.0381)
						)
					)
					(width 0)
					(fill yes)
				)
			)
		)
		(pad "A34" smd custom
			(at -8.919972 -25.103074)
			(size 0.10795 0.10795)
			(layers "F.Cu" "F.Mask" "F.Paste")
			(net "M_H_DQS_DN<14>")
			(options
				(clearance outline)
				(anchor circle)
			)
			(primitives
				(gr_poly
					(pts
						(arc
							(start 0.2159 -0.0381)
							(mid 0 -0.254)
							(end -0.2159 -0.0381)
						)
						(arc
							(start -0.2159 0.0381)
							(mid 0 0.254)
							(end 0.2159 0.0381)
						)
					)
					(width 0)
					(fill yes)
				)
			)
		)
		(pad "A36" smd custom
			(at -7.202932 -25.103074)
			(size 0.10795 0.10795)
			(layers "F.Cu" "F.Mask" "F.Paste")
			(net "GND")
			(options
				(clearance outline)
				(anchor circle)
			)
			(primitives
				(gr_poly
					(pts
						(arc
							(start 0.2159 -0.0381)
							(mid 0 -0.254)
							(end -0.2159 -0.0381)
						)
						(arc
							(start -0.2159 0.0381)
							(mid 0 0.254)
							(end 0.2159 0.0381)
						)
					)
					(width 0)
					(fill yes)
				)
			)
		)
		(pad "A38" smd custom
			(at -5.485892 -25.103074)
			(size 0.10795 0.10795)
			(layers "F.Cu" "F.Mask" "F.Paste")
			(net "GND")
			(options
				(clearance outline)
				(anchor circle)
			)
			(primitives
				(gr_poly
					(pts
						(arc
							(start 0.2159 -0.0381)
							(mid 0 -0.254)
							(end -0.2159 -0.0381)
						)
						(arc
							(start -0.2159 0.0381)
							(mid 0 0.254)
							(end 0.2159 0.0381)
						)
					)
					(width 0)
					(fill yes)
				)
			)
		)
		(pad "A40" smd custom
			(at -3.769106 -25.103074)
			(size 0.10795 0.10795)
			(layers "F.Cu" "F.Mask" "F.Paste")
			(net "M_G_DQS_DN<13>")
			(options
				(clearance outline)
				(anchor circle)
			)
			(primitives
				(gr_poly
					(pts
						(arc
							(start 0.2159 -0.0381)
							(mid 0 -0.254)
							(end -0.2159 -0.0381)
						)
						(arc
							(start -0.2159 0.0381)
							(mid 0 0.254)
							(end 0.2159 0.0381)
						)
					)
					(width 0)
					(fill yes)
				)
			)
		)
		(pad "A42" smd custom
			(at -2.052066 -25.103074 315)
			(size 0.10795 0.10795)
			(layers "F.Cu" "F.Mask" "F.Paste")
			(net "GND")
			(options
				(clearance outline)
				(anchor circle)
			)
			(primitives
				(gr_poly
					(pts
						(arc
							(start 0.2159 -0.0381)
							(mid 0 -0.254)
							(end -0.2159 -0.0381)
						)
						(arc
							(start -0.2159 0.0381)
							(mid 0 0.254)
							(end 0.2159 0.0381)
						)
					)
					(width 0)
					(fill yes)
				)
			)
		)
		(pad "AA2" smd circle
			(at -36.392104 -15.197074)
			(size 0.4318 0.4318)
			(layers "F.Cu" "F.Mask" "F.Paste")
			(net "UPI_CPU1_CPU0_P0P0_DP<4>")
		)
		(pad "AA4" smd circle
			(at -34.675064 -15.197074)
			(size 0.4318 0.4318)
			(layers "F.Cu" "F.Mask" "F.Paste")
			(net "GND")
		)
		(pad "AA6" smd circle
			(at -32.958024 -15.197074)
			(size 0.4318 0.4318)
			(layers "F.Cu" "F.Mask" "F.Paste")
			(net "UPI_CPU0_CPU1_P0P0_DP<2>")
		)
		(pad "AA8" smd circle
			(at -31.240984 -15.197074)
			(size 0.4318 0.4318)
			(layers "F.Cu" "F.Mask" "F.Paste")
			(net "UPI_CPU0_CPU1_P0P0_DN<1>")
		)
		(pad "AA10" smd circle
			(at -29.523944 -15.197074)
			(size 0.4318 0.4318)
			(layers "F.Cu" "F.Mask" "F.Paste")
			(net "PVCCIO_CPU1")
		)
		(pad "AA12" smd circle
			(at -27.806904 -15.197074)
			(size 0.4318 0.4318)
			(layers "F.Cu" "F.Mask" "F.Paste")
			(net "TP_XDP_CPU1_OBSDATA_B2_MBP4_N")
		)
		(pad "AA14" smd circle
			(at -26.090118 -15.197074)
			(size 0.4318 0.4318)
			(layers "F.Cu" "F.Mask" "F.Paste")
			(net "XDP_CPU_TCK0")
		)
		(pad "AA16" smd circle
			(at -24.373078 -15.197074)
			(size 0.4318 0.4318)
			(layers "F.Cu" "F.Mask" "F.Paste")
			(net "GND")
		)
		(pad "AA18" smd circle
			(at -22.656038 -15.197074)
			(size 0.4318 0.4318)
			(layers "F.Cu" "F.Mask" "F.Paste")
			(net "GND")
		)
		(pad "AA20" smd circle
			(at -20.938998 -15.197074)
			(size 0.4318 0.4318)
			(layers "F.Cu" "F.Mask" "F.Paste")
			(net "UPI_CPU0_CPU1_P1P1_DN<19>")
		)
		(pad "AA22" smd circle
			(at -19.221958 -15.197074)
			(size 0.4318 0.4318)
			(layers "F.Cu" "F.Mask" "F.Paste")
			(net "GND")
		)
		(pad "AA24" smd circle
			(at -17.504918 -15.197074)
			(size 0.4318 0.4318)
			(layers "F.Cu" "F.Mask" "F.Paste")
			(net "GND")
		)
		(pad "AA26" smd circle
			(at -15.787878 -15.197074)
			(size 0.4318 0.4318)
			(layers "F.Cu" "F.Mask" "F.Paste")
			(net "M_H_DQ<63>")
		)
		(pad "AA28" smd circle
			(at -14.071092 -15.197074)
			(size 0.4318 0.4318)
			(layers "F.Cu" "F.Mask" "F.Paste")
			(net "M_H_DQ<57>")
		)
		(pad "AA30" smd circle
			(at -12.354052 -15.197074)
			(size 0.4318 0.4318)
			(layers "F.Cu" "F.Mask" "F.Paste")
			(net "GND")
		)
		(pad "AA32" smd circle
			(at -10.637012 -15.197074)
			(size 0.4318 0.4318)
			(layers "F.Cu" "F.Mask" "F.Paste")
			(net "M_J_DQ<47>")
		)
		(pad "AA34" smd circle
			(at -8.919972 -15.197074)
			(size 0.4318 0.4318)
			(layers "F.Cu" "F.Mask" "F.Paste")
			(net "M_J_DQ<41>")
		)
		(pad "AA36" smd circle
			(at -7.202932 -15.197074)
			(size 0.4318 0.4318)
			(layers "F.Cu" "F.Mask" "F.Paste")
			(net "GND")
		)
		(pad "AA38" smd circle
			(at -5.485892 -15.197074)
			(size 0.4318 0.4318)
			(layers "F.Cu" "F.Mask" "F.Paste")
			(net "M_J_DQ<39>")
		)
		(pad "AA40" smd circle
			(at -3.769106 -15.197074)
			(size 0.4318 0.4318)
			(layers "F.Cu" "F.Mask" "F.Paste")
			(net "M_J_DQ<33>")
		)
		(pad "AA42" smd circle
			(at -2.052066 -15.197074)
			(size 0.4318 0.4318)
			(layers "F.Cu" "F.Mask" "F.Paste")
			(net "GND")
		)
		(pad "AA46" smd circle
			(at 2.910586 -16.997172)
			(size 0.4318 0.4318)
			(layers "F.Cu" "F.Mask" "F.Paste")
			(net "M_J_CS_N<3>")
		)
		(pad "AA48" smd circle
			(at 4.627626 -16.997172)
			(size 0.4318 0.4318)
			(layers "F.Cu" "F.Mask" "F.Paste")
			(net "M_J_ODT<1>")
		)
		(pad "AA50" smd circle
			(at 6.344412 -16.997172)
			(size 0.4318 0.4318)
			(layers "F.Cu" "F.Mask" "F.Paste")
			(net "M_J_ODT<0>")
		)
		(pad "AA52" smd circle
			(at 8.061452 -16.997172)
			(size 0.4318 0.4318)
			(layers "F.Cu" "F.Mask" "F.Paste")
			(net "M_J_MA<16>")
		)
		(pad "AA54" smd circle
			(at 9.778492 -16.997172)
			(size 0.4318 0.4318)
			(layers "F.Cu" "F.Mask" "F.Paste")
			(net "M_J_CLK_DN<0>")
		)
		(pad "AA56" smd circle
			(at 11.495532 -16.997172)
			(size 0.4318 0.4318)
			(layers "F.Cu" "F.Mask" "F.Paste")
			(net "M_J_CLK_DN<2>")
		)
		(pad "AA58" smd circle
			(at 13.212572 -16.997172)
			(size 0.4318 0.4318)
			(layers "F.Cu" "F.Mask" "F.Paste")
			(net "M_J_MA<4>")
		)
		(pad "AA60" smd circle
			(at 14.929612 -16.997172)
			(size 0.4318 0.4318)
			(layers "F.Cu" "F.Mask" "F.Paste")
			(net "M_J_BG<0>")
		)
		(pad "AA62" smd circle
			(at 16.646398 -16.997172)
			(size 0.4318 0.4318)
			(layers "F.Cu" "F.Mask" "F.Paste")
			(net "M_J_CKE<0>")
		)
		(pad "AA64" smd circle
			(at 18.363438 -16.997172)
			(size 0.4318 0.4318)
			(layers "F.Cu" "F.Mask" "F.Paste")
			(net "GND")
		)
		(pad "AA66" smd circle
			(at 20.080478 -16.997172)
			(size 0.4318 0.4318)
			(layers "F.Cu" "F.Mask" "F.Paste")
			(net "GND")
		)
		(pad "AA68" smd circle
			(at 21.797518 -16.997172)
			(size 0.4318 0.4318)
			(layers "F.Cu" "F.Mask" "F.Paste")
			(net "GND")
		)
		(pad "AA70" smd circle
			(at 23.514558 -16.997172)
			(size 0.4318 0.4318)
			(layers "F.Cu" "F.Mask" "F.Paste")
			(net "M_J_DQ<17>")
		)
		(pad "AA72" smd circle
			(at 25.231598 -16.997172)
			(size 0.4318 0.4318)
			(layers "F.Cu" "F.Mask" "F.Paste")
			(net "M_J_DQ<20>")
		)
		(pad "AA74" smd circle
			(at 26.948384 -16.997172)
			(size 0.4318 0.4318)
			(layers "F.Cu" "F.Mask" "F.Paste")
			(net "M_J_DQS_DN<1>")
		)
		(pad "AA76" smd circle
			(at 28.665424 -16.997172)
			(size 0.4318 0.4318)
			(layers "F.Cu" "F.Mask" "F.Paste")
			(net "GND")
		)
		(pad "AA78" smd circle
			(at 30.382464 -16.997172)
			(size 0.4318 0.4318)
			(layers "F.Cu" "F.Mask" "F.Paste")
			(net "GND")
		)
		(pad "AA80" smd circle
			(at 32.099504 -16.997172)
			(size 0.4318 0.4318)
			(layers "F.Cu" "F.Mask" "F.Paste")
			(net "GND")
		)
		(pad "AA82" smd circle
			(at 33.816544 -16.997172)
			(size 0.4318 0.4318)
			(layers "F.Cu" "F.Mask" "F.Paste")
			(net "GND")
		)
		(pad "AA84" smd circle
			(at 35.533584 -16.997172)
			(size 0.4318 0.4318)
			(layers "F.Cu" "F.Mask" "F.Paste")
			(net "M_G_DQ<13>")
		)
		(pad "AA86" smd custom
			(at 37.250624 -16.997172 270)
			(size 0.10795 0.10795)
			(layers "F.Cu" "F.Mask" "F.Paste")
			(net "M_G_DQ<12>")
			(options
				(clearance outline)
				(anchor circle)
			)
			(primitives
				(gr_poly
					(pts
						(arc
							(start 0.2159 -0.0381)
							(mid 0 -0.254)
							(end -0.2159 -0.0381)
						)
						(arc
							(start -0.2159 0.0381)
							(mid 0 0.254)
							(end 0.2159 0.0381)
						)
					)
					(width 0)
					(fill yes)
				)
			)
		)
		(pad "AB1" smd custom
			(at -37.250624 -14.702028 90)
			(size 0.10795 0.10795)
			(layers "F.Cu" "F.Mask" "F.Paste")
			(net "GND")
			(options
				(clearance outline)
				(anchor circle)
			)
			(primitives
				(gr_poly
					(pts
						(arc
							(start 0.2159 -0.0381)
							(mid 0 -0.254)
							(end -0.2159 -0.0381)
						)
						(arc
							(start -0.2159 0.0381)
							(mid 0 0.254)
							(end 0.2159 0.0381)
						)
					)
					(width 0)
					(fill yes)
				)
			)
		)
		(pad "AB3" smd circle
			(at -35.533584 -14.702028)
			(size 0.4318 0.4318)
			(layers "F.Cu" "F.Mask" "F.Paste")
			(net "UPI_CPU1_CPU0_P0P0_DN<4>")
		)
		(pad "AB5" smd circle
			(at -33.816544 -14.702028)
			(size 0.4318 0.4318)
			(layers "F.Cu" "F.Mask" "F.Paste")
			(net "GND")
		)
		(pad "AB7" smd circle
			(at -32.099504 -14.702028)
			(size 0.4318 0.4318)
			(layers "F.Cu" "F.Mask" "F.Paste")
			(net "UPI_CPU0_CPU1_P0P0_DN<2>")
		)
		(pad "AB9" smd circle
			(at -30.382464 -14.702028)
			(size 0.4318 0.4318)
			(layers "F.Cu" "F.Mask" "F.Paste")
			(net "UPI_CPU0_CPU1_P0P0_DN<0>")
		)
		(pad "AB11" smd circle
			(at -28.665424 -14.702028)
			(size 0.4318 0.4318)
			(layers "F.Cu" "F.Mask" "F.Paste")
			(net "GND")
		)
		(pad "AB13" smd circle
			(at -26.948384 -14.702028)
			(size 0.4318 0.4318)
			(layers "F.Cu" "F.Mask" "F.Paste")
			(net "FM_CPU1_SKTOCC_LVT3_N")
		)
		(pad "AB15" smd circle
			(at -25.231598 -14.702028)
			(size 0.4318 0.4318)
			(layers "F.Cu" "F.Mask" "F.Paste")
			(net "H_CPU1_THERMTRIP_G_N")
		)
		(pad "AB17" smd circle
			(at -23.514558 -14.702028)
			(size 0.4318 0.4318)
			(layers "F.Cu" "F.Mask" "F.Paste")
			(net "TP_CPU1_PROC_DIS_G_N")
		)
		(pad "AB19" smd circle
			(at -21.797518 -14.702028)
			(size 0.4318 0.4318)
			(layers "F.Cu" "F.Mask" "F.Paste")
			(net "UPI_CPU0_CPU1_P1P1_DP<19>")
		)
		(pad "AB21" smd circle
			(at -20.080478 -14.702028)
			(size 0.4318 0.4318)
			(layers "F.Cu" "F.Mask" "F.Paste")
			(net "GND")
		)
		(pad "AB23" smd circle
			(at -18.363438 -14.702028)
			(size 0.4318 0.4318)
			(layers "F.Cu" "F.Mask" "F.Paste")
			(net "GND")
		)
		(pad "AB25" smd circle
			(at -16.646398 -14.702028)
			(size 0.4318 0.4318)
			(layers "F.Cu" "F.Mask" "F.Paste")
			(net "GND")
		)
		(pad "AB27" smd circle
			(at -14.929612 -14.702028)
			(size 0.4318 0.4318)
			(layers "F.Cu" "F.Mask" "F.Paste")
			(net "M_H_DQS_DN<7>")
		)
		(pad "AB29" smd circle
			(at -13.212572 -14.702028)
			(size 0.4318 0.4318)
			(layers "F.Cu" "F.Mask" "F.Paste")
			(net "GND")
		)
		(pad "AB31" smd circle
			(at -11.495532 -14.702028)
			(size 0.4318 0.4318)
			(layers "F.Cu" "F.Mask" "F.Paste")
			(net "GND")
		)
		(pad "AB33" smd circle
			(at -9.778492 -14.702028)
			(size 0.4318 0.4318)
			(layers "F.Cu" "F.Mask" "F.Paste")
			(net "M_J_DQS_DN<5>")
		)
		(pad "AB35" smd circle
			(at -8.061452 -14.702028)
			(size 0.4318 0.4318)
			(layers "F.Cu" "F.Mask" "F.Paste")
			(net "GND")
		)
		(pad "AB37" smd circle
			(at -6.344412 -14.702028)
			(size 0.4318 0.4318)
			(layers "F.Cu" "F.Mask" "F.Paste")
			(net "GND")
		)
		(pad "AB39" smd circle
			(at -4.627626 -14.702028)
			(size 0.4318 0.4318)
			(layers "F.Cu" "F.Mask" "F.Paste")
			(net "M_J_DQS_DN<4>")
		)
	)
)
